# SCM (Grand Teton) — schematic netlist excerpt (pin names and nets, part order shuffled) for the footprints in the layout excerpt that follows; sources: Cadence DE-HDL packaged netlist, KiCad conversion of 12092022_DA0F0TMDCD0_F0T_Management_Board_D_brd_V3_OCP.brd

C198  Q_CAP  1UF 25V 10% X6S  pkg C0402  page 50 : A = REAR_PWR_BTN_N ; B = GND
PC206  Q_CAP  22UF 16V 20% X6S  pkg C0805  page 51 : A = SW_P5V_AUX_FLT ; B = GND
R829  Q_RES  25.5K 1% CHIP  pkg 0402LF  page 53 : A = P2V5_AUX ; B = U39_ADJ

(kicad_pcb
	(version 20260206)
	(generator "pcbnew")
	(generator_version "10.0")
	(general
		(thickness 1.6)
		(legacy_teardrops no)
	)
	(paper "A4")
	(title_block
		(title "12092022_DA0F0TMDCD0_F0T_Management_Board_D_brd_V3_OCP.brd")
		(comment 1 "Grand Teton / footprints 705-707 of 1440")
	)
	(layers
		(0 "F.Cu" signal "TOP")
		(4 "In1.Cu" signal "GND")
		(6 "In2.Cu" signal "IN1")
		(8 "In3.Cu" signal "GND1")
		(10 "In4.Cu" signal "IN2")
		(12 "In5.Cu" signal "VCC")
		(14 "In6.Cu" signal "VCC1")
		(16 "In7.Cu" signal "IN3")
		(18 "In8.Cu" signal "GND2")
		(20 "In9.Cu" signal "IN4")
		(22 "In10.Cu" signal "GND3")
		(2 "B.Cu" signal "BOTTOM")
		(9 "F.Adhes" user "F.Adhesive")
		(11 "B.Adhes" user "B.Adhesive")
		(13 "F.Paste" user "Package Geometry/Pastemask Top")
		(15 "B.Paste" user "Package Geometry/Pastemask Bottom")
		(5 "F.SilkS" user "Ref Des/Silkscreen Top")
		(7 "B.SilkS" user "Ref Des/Silkscreen Bottom")
		(1 "F.Mask" user "Board Geometry/Soldermask Top")
		(3 "B.Mask" user "Board Geometry/Soldermask Bottom")
		(17 "Dwgs.User" user "User.Drawings")
		(19 "Cmts.User" user "User.Comments")
		(21 "Eco1.User" user "User.Eco1")
		(23 "Eco2.User" user "User.Eco2")
		(25 "Edge.Cuts" user "Board Geometry/Outline")
		(27 "Margin" user)
		(31 "F.CrtYd" user "Package Geometry/Place Bound Top")
		(29 "B.CrtYd" user "Package Geometry/Place Bound Bottom")
		(35 "F.Fab" user "Ref Des/Assembly Top")
		(33 "B.Fab" user "Ref Des/Assembly Bottom")
	)
	(footprint ""
		(layer "F.Cu")
		(at 83.217258 -36.683442 180)
		(property "Reference" "R829"
			(at 0 0 180)
			(layer "F.SilkS")
			(hide yes)
			(effects
				(font
					(size 1.27 1.27)
				)
			)
		)
		(property "Value" ""
			(at 0 0 180)
			(layer "F.Fab")
			(effects
				(font
					(size 1.27 1.27)
				)
			)
		)
		(duplicate_pad_numbers_are_jumpers no)
		(fp_line
			(start 0.7874 0.4064)
			(end -0.7874 0.4064)
			(stroke
				(width 0.1524)
				(type default)
			)
			(layer "F.SilkS")
		)
		(fp_line
			(start 0.7874 -0.4064)
			(end 0.7874 0.4064)
			(stroke
				(width 0.1524)
				(type default)
			)
			(layer "F.SilkS")
		)
		(fp_line
			(start -0.7874 0.4064)
			(end -0.7874 -0.4064)
			(stroke
				(width 0.1524)
				(type default)
			)
			(layer "F.SilkS")
		)
		(fp_line
			(start -0.7874 -0.4064)
			(end 0.7874 -0.4064)
			(stroke
				(width 0.1524)
				(type default)
			)
			(layer "F.SilkS")
		)
		(fp_line
			(start 0.67945 0.3048)
			(end 0.120396 0.3048)
			(stroke
				(width 0.1)
				(type default)
			)
			(layer "F.Fab")
		)
		(fp_line
			(start 0.67945 -0.3048)
			(end 0.67945 0.3048)
			(stroke
				(width 0.1)
				(type default)
			)
			(layer "F.Fab")
		)
		(fp_line
			(start 0.12065 -0.2794)
			(end 0.12065 -0.3048)
			(stroke
				(width 0.1)
				(type default)
			)
			(layer "F.Fab")
		)
		(fp_line
			(start 0.12065 -0.3048)
			(end 0.67945 -0.3048)
			(stroke
				(width 0.1)
				(type default)
			)
			(layer "F.Fab")
		)
		(fp_line
			(start 0.120396 0.3048)
			(end 0.120396 0.2794)
			(stroke
				(width 0.1)
				(type default)
			)
			(layer "F.Fab")
		)
		(fp_line
			(start 0.120396 0.2794)
			(end -0.12065 0.2794)
			(stroke
				(width 0.1)
				(type default)
			)
			(layer "F.Fab")
		)
		(fp_line
			(start -0.12065 0.3048)
			(end -0.67945 0.3048)
			(stroke
				(width 0.1)
				(type default)
			)
			(layer "F.Fab")
		)
		(fp_line
			(start -0.12065 0.2794)
			(end -0.12065 0.3048)
			(stroke
				(width 0.1)
				(type default)
			)
			(layer "F.Fab")
		)
		(fp_line
			(start -0.12065 -0.2794)
			(end 0.12065 -0.2794)
			(stroke
				(width 0.1)
				(type default)
			)
			(layer "F.Fab")
		)
		(fp_line
			(start -0.12065 -0.305054)
			(end -0.12065 -0.2794)
			(stroke
				(width 0.1)
				(type default)
			)
			(layer "F.Fab")
		)
		(fp_line
			(start -0.67945 0.3048)
			(end -0.67945 -0.305054)
			(stroke
				(width 0.1)
				(type default)
			)
			(layer "F.Fab")
		)
		(fp_line
			(start -0.67945 -0.305054)
			(end -0.12065 -0.305054)
			(stroke
				(width 0.1)
				(type default)
			)
			(layer "F.Fab")
		)
		(pad "1" smd circle
			(at -0.40005 0 180)
			(size 0 0)
			(layers "F.Cu" "F.Mask" "F.Paste")
			(net "P2V5_AUX")
		)
		(pad "2" smd circle
			(at 0.40005 0 180)
			(size 0 0)
			(layers "F.Cu" "F.Mask" "F.Paste")
			(net "U39_ADJ")
		)
	)
	(footprint ""
		(layer "F.Cu")
		(at 6.096 -55.372 180)
		(property "Reference" "PC206"
			(at 0 0 180)
			(layer "F.SilkS")
			(hide yes)
			(effects
				(font
					(size 1.27 1.27)
				)
			)
		)
		(property "Value" ""
			(at 0 0 180)
			(layer "F.Fab")
			(effects
				(font
					(size 1.27 1.27)
				)
			)
		)
		(duplicate_pad_numbers_are_jumpers no)
		(fp_line
			(start 1.524 0.762)
			(end -1.524 0.762)
			(stroke
				(width 0.1524)
				(type default)
			)
			(layer "F.SilkS")
		)
		(fp_line
			(start 1.524 -0.762)
			(end 1.524 0.762)
			(stroke
				(width 0.1524)
				(type default)
			)
			(layer "F.SilkS")
		)
		(fp_line
			(start -1.524 0.762)
			(end -1.524 -0.762)
			(stroke
				(width 0.1524)
				(type default)
			)
			(layer "F.SilkS")
		)
		(fp_line
			(start -1.524 -0.762)
			(end 1.524 -0.762)
			(stroke
				(width 0.1524)
				(type default)
			)
			(layer "F.SilkS")
		)
		(fp_line
			(start 1.1049 0.724916)
			(end 1.1049 -0.724916)
			(stroke
				(width 0.1)
				(type default)
			)
			(layer "F.Fab")
		)
		(fp_line
			(start 1.1049 -0.724916)
			(end -1.1049 -0.724916)
			(stroke
				(width 0.1)
				(type default)
			)
			(layer "F.Fab")
		)
		(fp_line
			(start -1.1049 0.724916)
			(end 1.1049 0.724916)
			(stroke
				(width 0.1)
				(type default)
			)
			(layer "F.Fab")
		)
		(fp_line
			(start -1.1049 -0.724916)
			(end -1.1049 0.724916)
			(stroke
				(width 0.1)
				(type default)
			)
			(layer "F.Fab")
		)
		(pad "1" smd rect
			(at -0.889 0)
			(size 1.016 1.27)
			(layers "F.Cu" "F.Mask" "F.Paste")
			(net "SW_P5V_AUX_FLT")
		)
		(pad "2" smd rect
			(at 0.889 0)
			(size 1.016 1.27)
			(layers "F.Cu" "F.Mask" "F.Paste")
			(net "GND")
		)
	)
	(footprint ""
		(layer "F.Cu")
		(at 9.779 -9.652 180)
		(property "Reference" "C198"
			(at 0 0 180)
			(layer "F.SilkS")
			(hide yes)
			(effects
				(font
					(size 1.27 1.27)
				)
			)
		)
		(property "Value" ""
			(at 0 0 180)
			(layer "F.Fab")
			(effects
				(font
					(size 1.27 1.27)
				)
			)
		)
		(duplicate_pad_numbers_are_jumpers no)
		(fp_line
			(start 0.7874 0.4064)
			(end -0.7874 0.4064)
			(stroke
				(width 0.1524)
				(type default)
			)
			(layer "F.SilkS")
		)
		(fp_line
			(start 0.7874 -0.4064)
			(end 0.7874 0.4064)
			(stroke
				(width 0.1524)
				(type default)
			)
			(layer "F.SilkS")
		)
		(fp_line
			(start -0.7874 0.4064)
			(end -0.7874 -0.4064)
			(stroke
				(width 0.1524)
				(type default)
			)
			(layer "F.SilkS")
		)
		(fp_line
			(start -0.7874 -0.4064)
			(end 0.7874 -0.4064)
			(stroke
				(width 0.1524)
				(type default)
			)
			(layer "F.SilkS")
		)
		(fp_line
			(start 0.67945 0.3048)
			(end 0.120396 0.3048)
			(stroke
				(width 0.1)
				(type default)
			)
			(layer "F.Fab")
		)
		(fp_line
			(start 0.67945 -0.3048)
			(end 0.67945 0.3048)
			(stroke
				(width 0.1)
				(type default)
			)
			(layer "F.Fab")
		)
		(fp_line
			(start 0.12065 -0.2794)
			(end 0.12065 -0.3048)
			(stroke
				(width 0.1)
				(type default)
			)
			(layer "F.Fab")
		)
		(fp_line
			(start 0.12065 -0.3048)
			(end 0.67945 -0.3048)
			(stroke
				(width 0.1)
				(type default)
			)
			(layer "F.Fab")
		)
		(fp_line
			(start 0.120396 0.3048)
			(end 0.120396 0.2794)
			(stroke
				(width 0.1)
				(type default)
			)
			(layer "F.Fab")
		)
		(fp_line
			(start 0.120396 0.2794)
			(end -0.12065 0.2794)
			(stroke
				(width 0.1)
				(type default)
			)
			(layer "F.Fab")
		)
		(fp_line
			(start -0.12065 0.3048)
			(end -0.67945 0.3048)
			(stroke
				(width 0.1)
				(type default)
			)
			(layer "F.Fab")
		)
		(fp_line
			(start -0.12065 0.2794)
			(end -0.12065 0.3048)
			(stroke
				(width 0.1)
				(type default)
			)
			(layer "F.Fab")
		)
		(fp_line
			(start -0.12065 -0.2794)
			(end 0.12065 -0.2794)
			(stroke
				(width 0.1)
				(type default)
			)
			(layer "F.Fab")
		)
		(fp_line
			(start -0.12065 -0.305054)
			(end -0.12065 -0.2794)
			(stroke
				(width 0.1)
				(type default)
			)
			(layer "F.Fab")
		)
		(fp_line
			(start -0.67945 0.3048)
			(end -0.67945 -0.305054)
			(stroke
				(width 0.1)
				(type default)
			)
			(layer "F.Fab")
		)
		(fp_line
			(start -0.67945 -0.305054)
			(end -0.12065 -0.305054)
			(stroke
				(width 0.1)
				(type default)
			)
			(layer "F.Fab")
		)
		(pad "1" smd circle
			(at -0.40005 0 180)
			(size 0 0)
			(layers "F.Cu" "F.Mask" "F.Paste")
			(net "REAR_PWR_BTN_N")
		)
		(pad "2" smd circle
			(at 0.40005 0 180)
			(size 0 0)
			(layers "F.Cu" "F.Mask" "F.Paste")
			(net "GND")
		)
	)
)
